# BASEBOARD_FAB2 (Tioga Pass) — schematic netlist excerpt (pin names and nets, part order shuffled) for the footprints in the layout excerpt that follows; sources: Cadence DE-HDL packaged netlist, KiCad conversion of Wiwynn_Tioga_Pass_MB.brd

R7B6  RES  10.0K 1% CHIP  pkg 0402  page 133 : A = P3V3_STBY ; B = FM_PCH_PRSNT_N
RT8P1  RES  100.0K 1% CHIP  pkg 0603  page 71 : A = PVCCIN_CPU1 ; B = VSENSE_VCCINR2PMAX_CPU1
R1U41  RES  150.0 1% CHIP  pkg 0402  page 152 : A = PVCCIO_CPU1 ; B = H_CPU1_MEMGHJ_MEMHOT_G_N

(kicad_pcb
	(version 20260206)
	(generator "pcbnew")
	(generator_version "10.0")
	(general
		(thickness 1.6)
		(legacy_teardrops no)
	)
	(paper "A4")
	(title_block
		(title "Wiwynn_Tioga_Pass_MB.brd")
		(comment 1 "Tioga Pass / footprints 468-470 of 4770")
	)
	(layers
		(0 "F.Cu" signal "TOP")
		(4 "In1.Cu" signal "L2GND")
		(6 "In2.Cu" signal "L3")
		(8 "In3.Cu" signal "L4GND")
		(10 "In4.Cu" signal "L5")
		(12 "In5.Cu" signal "L6GND")
		(14 "In6.Cu" signal "L7VCC")
		(16 "In7.Cu" signal "L8VCC")
		(18 "In8.Cu" signal "L9GND")
		(20 "In9.Cu" signal "L10")
		(22 "In10.Cu" signal "L11GND")
		(24 "In11.Cu" signal "L12")
		(26 "In12.Cu" signal "L13GND")
		(2 "B.Cu" signal "BOTTOM")
		(9 "F.Adhes" user "F.Adhesive")
		(11 "B.Adhes" user "B.Adhesive")
		(13 "F.Paste" user "Package Geometry/Pastemask Top")
		(15 "B.Paste" user "Package Geometry/Pastemask Bottom")
		(5 "F.SilkS" user "Ref Des/Silkscreen Top")
		(7 "B.SilkS" user "Ref Des/Silkscreen Bottom")
		(1 "F.Mask" user "Board Geometry/Soldermask Top")
		(3 "B.Mask" user "Board Geometry/Soldermask Bottom")
		(17 "Dwgs.User" user "User.Drawings")
		(19 "Cmts.User" user "User.Comments")
		(21 "Eco1.User" user "User.Eco1")
		(23 "Eco2.User" user "User.Eco2")
		(25 "Edge.Cuts" user "Board Geometry/Outline")
		(27 "Margin" user)
		(31 "F.CrtYd" user "Package Geometry/Place Bound Top")
		(29 "B.CrtYd" user "Package Geometry/Place Bound Bottom")
		(35 "F.Fab" user "Ref Des/Assembly Top")
		(33 "B.Fab" user "Ref Des/Assembly Bottom")
	)
	(footprint ""
		(layer "F.Cu")
		(at 436.8165 -15.367 90)
		(property "Reference" "R1U41"
			(at 0 0 90)
			(layer "F.SilkS")
			(hide yes)
			(effects
				(font
					(size 1.27 1.27)
				)
			)
		)
		(property "Value" ""
			(at 0 0 90)
			(layer "F.Fab")
			(effects
				(font
					(size 1.27 1.27)
				)
			)
		)
		(duplicate_pad_numbers_are_jumpers no)
		(fp_poly
			(pts
				(xy -0.2794 -0.1016) (xy 0.2794 -0.1016) (xy 0.2794 0.9906) (xy -0.2794 0.9906)
			)
			(stroke
				(width 0)
				(type default)
			)
			(fill no)
			(layer "F.CrtYd")
		)
		(fp_line
			(start 0.2794 -0.1016)
			(end -0.2794 -0.1016)
			(stroke
				(width 0.1)
				(type default)
			)
			(layer "F.Fab")
		)
		(fp_line
			(start -0.2794 -0.1016)
			(end -0.2794 0.9906)
			(stroke
				(width 0.1)
				(type default)
			)
			(layer "F.Fab")
		)
		(fp_line
			(start 0.2794 0.9906)
			(end 0.2794 -0.1016)
			(stroke
				(width 0.1)
				(type default)
			)
			(layer "F.Fab")
		)
		(fp_line
			(start -0.2794 0.9906)
			(end 0.2794 0.9906)
			(stroke
				(width 0.1)
				(type default)
			)
			(layer "F.Fab")
		)
		(pad "1" smd rect
			(at 0 0 90)
			(size 0.508 0.508)
			(layers "F.Cu" "F.Mask" "F.Paste")
			(net "PVCCIO_CPU1")
		)
		(pad "2" smd rect
			(at 0 0.889 90)
			(size 0.508 0.508)
			(layers "F.Cu" "F.Mask" "F.Paste")
			(net "H_CPU1_MEMGHJ_MEMHOT_G_N")
		)
		(zone
			(layer "F.Cu")
			(hatch none 0.5)
			(connect_pads
				(clearance 0)
			)
			(min_thickness 0.25)
			(keepout
				(tracks allowed)
				(vias not_allowed)
				(pads allowed)
				(copperpour not_allowed)
				(footprints allowed)
			)
			(placement
				(enabled no)
				(sheetname "")
			)
			(fill
				(thermal_gap 0.5)
				(thermal_bridge_width 0.5)
				(island_removal_mode 0)
			)
			(polygon
				(pts
					(xy 437.0705 -15.113) (xy 437.0705 -15.621) (xy 437.4515 -15.621) (xy 437.4515 -15.113)
				)
			)
		)
		(zone
			(layer "F.Cu")
			(hatch none 0.5)
			(connect_pads
				(clearance 0)
			)
			(min_thickness 0.25)
			(keepout
				(tracks not_allowed)
				(vias allowed)
				(pads allowed)
				(copperpour not_allowed)
				(footprints allowed)
			)
			(placement
				(enabled no)
				(sheetname "")
			)
			(fill
				(thermal_gap 0.5)
				(thermal_bridge_width 0.5)
				(island_removal_mode 0)
			)
			(polygon
				(pts
					(xy 437.4515 -15.113) (xy 437.4515 -15.621) (xy 437.0705 -15.621) (xy 437.0705 -15.113)
				)
			)
		)
	)
	(footprint ""
		(layer "F.Cu")
		(at 44.1071 -51.3334 90)
		(property "Reference" "RT8P1"
			(at 1.27127 0.4699 180)
			(unlocked yes)
			(layer "F.SilkS")
			(effects
				(font
					(size 0.7874 0.5842)
					(thickness 0.1524)
				)
			)
		)
		(property "Value" ""
			(at 0 0 90)
			(layer "F.Fab")
			(effects
				(font
					(size 1.27 1.27)
				)
			)
		)
		(duplicate_pad_numbers_are_jumpers no)
		(fp_poly
			(pts
				(xy -0.4953 -0.2032) (xy 0.4953 -0.2032) (xy 0.4953 1.6002) (xy -0.4953 1.6002)
			)
			(stroke
				(width 0)
				(type default)
			)
			(fill no)
			(layer "F.CrtYd")
		)
		(fp_line
			(start 0.4953 -0.2032)
			(end 0.4953 1.6002)
			(stroke
				(width 0.1)
				(type default)
			)
			(layer "F.Fab")
		)
		(fp_line
			(start -0.4953 -0.2032)
			(end 0.4953 -0.2032)
			(stroke
				(width 0.1)
				(type default)
			)
			(layer "F.Fab")
		)
		(fp_line
			(start 0.4953 1.6002)
			(end -0.4953 1.6002)
			(stroke
				(width 0.1)
				(type default)
			)
			(layer "F.Fab")
		)
		(fp_line
			(start -0.4953 1.6002)
			(end -0.4953 -0.2032)
			(stroke
				(width 0.1)
				(type default)
			)
			(layer "F.Fab")
		)
		(pad "1" smd rect
			(at 0 0 90)
			(size 0.762 0.889)
			(layers "F.Cu" "F.Mask" "F.Paste")
			(net "PVCCIN_CPU1")
		)
		(pad "2" smd rect
			(at 0 1.397 90)
			(size 0.762 0.889)
			(layers "F.Cu" "F.Mask" "F.Paste")
			(net "VSENSE_VCCINR2PMAX_CPU1")
		)
		(zone
			(layer "F.Cu")
			(hatch none 0.5)
			(connect_pads
				(clearance 0)
			)
			(min_thickness 0.25)
			(keepout
				(tracks allowed)
				(vias not_allowed)
				(pads allowed)
				(copperpour not_allowed)
				(footprints allowed)
			)
			(placement
				(enabled no)
				(sheetname "")
			)
			(fill
				(thermal_gap 0.5)
				(thermal_bridge_width 0.5)
				(island_removal_mode 0)
			)
			(polygon
				(pts
					(xy 45.0596 -51.7144) (xy 44.5516 -51.7144) (xy 44.5516 -50.9524) (xy 45.0596 -50.9524)
				)
			)
		)
		(zone
			(layer "F.Cu")
			(hatch none 0.5)
			(connect_pads
				(clearance 0)
			)
			(min_thickness 0.25)
			(keepout
				(tracks not_allowed)
				(vias allowed)
				(pads allowed)
				(copperpour not_allowed)
				(footprints allowed)
			)
			(placement
				(enabled no)
				(sheetname "")
			)
			(fill
				(thermal_gap 0.5)
				(thermal_bridge_width 0.5)
				(island_removal_mode 0)
			)
			(polygon
				(pts
					(xy 45.0596 -50.9524) (xy 45.0596 -51.7144) (xy 44.5516 -51.7144) (xy 44.5516 -50.9524)
				)
			)
		)
	)
	(footprint ""
		(layer "F.Cu")
		(at 369.8494 -129.286 90)
		(property "Reference" "R7B6"
			(at 0 0 90)
			(layer "F.SilkS")
			(hide yes)
			(effects
				(font
					(size 1.27 1.27)
				)
			)
		)
		(property "Value" ""
			(at 0 0 90)
			(layer "F.Fab")
			(effects
				(font
					(size 1.27 1.27)
				)
			)
		)
		(duplicate_pad_numbers_are_jumpers no)
		(fp_poly
			(pts
				(xy -0.2794 -0.1016) (xy 0.2794 -0.1016) (xy 0.2794 0.9906) (xy -0.2794 0.9906)
			)
			(stroke
				(width 0)
				(type default)
			)
			(fill no)
			(layer "F.CrtYd")
		)
		(fp_line
			(start 0.2794 -0.1016)
			(end -0.2794 -0.1016)
			(stroke
				(width 0.1)
				(type default)
			)
			(layer "F.Fab")
		)
		(fp_line
			(start -0.2794 -0.1016)
			(end -0.2794 0.9906)
			(stroke
				(width 0.1)
				(type default)
			)
			(layer "F.Fab")
		)
		(fp_line
			(start 0.2794 0.9906)
			(end 0.2794 -0.1016)
			(stroke
				(width 0.1)
				(type default)
			)
			(layer "F.Fab")
		)
		(fp_line
			(start -0.2794 0.9906)
			(end 0.2794 0.9906)
			(stroke
				(width 0.1)
				(type default)
			)
			(layer "F.Fab")
		)
		(pad "1" smd rect
			(at 0 0 90)
			(size 0.508 0.508)
			(layers "F.Cu" "F.Mask" "F.Paste")
			(net "P3V3_STBY")
		)
		(pad "2" smd rect
			(at 0 0.889 90)
			(size 0.508 0.508)
			(layers "F.Cu" "F.Mask" "F.Paste")
			(net "FM_PCH_PRSNT_N")
		)
		(zone
			(layer "F.Cu")
			(hatch none 0.5)
			(connect_pads
				(clearance 0)
			)
			(min_thickness 0.25)
			(keepout
				(tracks allowed)
				(vias not_allowed)
				(pads allowed)
				(copperpour not_allowed)
				(footprints allowed)
			)
			(placement
				(enabled no)
				(sheetname "")
			)
			(fill
				(thermal_gap 0.5)
				(thermal_bridge_width 0.5)
				(island_removal_mode 0)
			)
			(polygon
				(pts
					(xy 370.1034 -129.032) (xy 370.1034 -129.54) (xy 370.4844 -129.54) (xy 370.4844 -129.032)
				)
			)
		)
		(zone
			(layer "F.Cu")
			(hatch none 0.5)
			(connect_pads
				(clearance 0)
			)
			(min_thickness 0.25)
			(keepout
				(tracks not_allowed)
				(vias allowed)
				(pads allowed)
				(copperpour not_allowed)
				(footprints allowed)
			)
			(placement
				(enabled no)
				(sheetname "")
			)
			(fill
				(thermal_gap 0.5)
				(thermal_bridge_width 0.5)
				(island_removal_mode 0)
			)
			(polygon
				(pts
					(xy 370.4844 -129.032) (xy 370.4844 -129.54) (xy 370.1034 -129.54) (xy 370.1034 -129.032)
				)
			)
		)
	)
)
